# BASEBOARD_FAB2 (Tioga Pass) — schematic netlist excerpt (pin names and nets, part order shuffled) for the footprints in the layout excerpt that follows; sources: Cadence DE-HDL packaged netlist, KiCad conversion of Wiwynn_Tioga_Pass_MB.brd

C8P11  CAP  47UF 4V 20% X6S  pkg 0805  page 76 : A = PVCCIN_CPU1 ; B = GND
R6R2  RES  0.0 5% CHIP  pkg 0402  page 202 : A = VR_PVCCIN_CPU0_PH1_VCIN ; B = P5V_STBY
C1L11  CAP_A  0.1UF 16V 10% X7R  pkg 0402V  page 111 : A = P3V3_STBY ; B = GND

(kicad_pcb
	(version 20260206)
	(generator "pcbnew")
	(generator_version "10.0")
	(general
		(thickness 1.6)
		(legacy_teardrops no)
	)
	(paper "A4")
	(title_block
		(title "Wiwynn_Tioga_Pass_MB.brd")
		(comment 1 "Tioga Pass / footprints 2509-2511 of 4770")
	)
	(layers
		(0 "F.Cu" signal "TOP")
		(4 "In1.Cu" signal "L2GND")
		(6 "In2.Cu" signal "L3")
		(8 "In3.Cu" signal "L4GND")
		(10 "In4.Cu" signal "L5")
		(12 "In5.Cu" signal "L6GND")
		(14 "In6.Cu" signal "L7VCC")
		(16 "In7.Cu" signal "L8VCC")
		(18 "In8.Cu" signal "L9GND")
		(20 "In9.Cu" signal "L10")
		(22 "In10.Cu" signal "L11GND")
		(24 "In11.Cu" signal "L12")
		(26 "In12.Cu" signal "L13GND")
		(2 "B.Cu" signal "BOTTOM")
		(9 "F.Adhes" user "F.Adhesive")
		(11 "B.Adhes" user "B.Adhesive")
		(13 "F.Paste" user "Package Geometry/Pastemask Top")
		(15 "B.Paste" user "Package Geometry/Pastemask Bottom")
		(5 "F.SilkS" user "Ref Des/Silkscreen Top")
		(7 "B.SilkS" user "Ref Des/Silkscreen Bottom")
		(1 "F.Mask" user "Board Geometry/Soldermask Top")
		(3 "B.Mask" user "Board Geometry/Soldermask Bottom")
		(17 "Dwgs.User" user "User.Drawings")
		(19 "Cmts.User" user "User.Comments")
		(21 "Eco1.User" user "User.Eco1")
		(23 "Eco2.User" user "User.Eco2")
		(25 "Edge.Cuts" user "Board Geometry/Outline")
		(27 "Margin" user)
		(31 "F.CrtYd" user "Package Geometry/Place Bound Top")
		(29 "B.CrtYd" user "Package Geometry/Place Bound Bottom")
		(35 "F.Fab" user "Ref Des/Assembly Top")
		(33 "B.Fab" user "Ref Des/Assembly Bottom")
	)
	(footprint ""
		(layer "B.Cu")
		(at 457.6064 -144.145 90)
		(property "Reference" "C1L11"
			(at 0 0 90)
			(layer "B.SilkS")
			(hide yes)
			(effects
				(font
					(size 1.27 1.27)
				)
				(justify mirror)
			)
		)
		(property "Value" ""
			(at 0 0 90)
			(layer "B.Fab")
			(effects
				(font
					(size 1.27 1.27)
				)
				(justify mirror)
			)
		)
		(duplicate_pad_numbers_are_jumpers no)
		(fp_poly
			(pts
				(xy -0.3048 -0.1016) (xy -0.3048 0.9906) (xy 0.3048 0.9906) (xy 0.3048 -0.1016)
			)
			(stroke
				(width 0)
				(type default)
			)
			(fill no)
			(layer "B.CrtYd")
		)
		(fp_line
			(start 0.3048 -0.1016)
			(end 0.3048 0.9906)
			(stroke
				(width 0.1)
				(type default)
			)
			(layer "B.Fab")
		)
		(fp_line
			(start -0.3048 -0.1016)
			(end 0.3048 -0.1016)
			(stroke
				(width 0.1)
				(type default)
			)
			(layer "B.Fab")
		)
		(fp_line
			(start 0.3048 0.9906)
			(end -0.3048 0.9906)
			(stroke
				(width 0.1)
				(type default)
			)
			(layer "B.Fab")
		)
		(fp_line
			(start -0.3048 0.9906)
			(end -0.3048 -0.1016)
			(stroke
				(width 0.1)
				(type default)
			)
			(layer "B.Fab")
		)
		(pad "1" smd rect
			(at 0 0 270)
			(size 0.508 0.508)
			(layers "B.Cu" "B.Mask" "B.Paste")
			(net "P3V3_STBY")
		)
		(pad "2" smd rect
			(at 0 0.889 270)
			(size 0.508 0.508)
			(layers "B.Cu" "B.Mask" "B.Paste")
			(net "GND")
		)
		(zone
			(layer "B.Cu")
			(hatch none 0.5)
			(connect_pads
				(clearance 0)
			)
			(min_thickness 0.25)
			(keepout
				(tracks allowed)
				(vias not_allowed)
				(pads allowed)
				(copperpour not_allowed)
				(footprints allowed)
			)
			(placement
				(enabled no)
				(sheetname "")
			)
			(fill
				(thermal_gap 0.5)
				(thermal_bridge_width 0.5)
				(island_removal_mode 0)
			)
			(polygon
				(pts
					(xy 457.8604 -144.399) (xy 457.8604 -143.891) (xy 458.2414 -143.891) (xy 458.2414 -144.399)
				)
			)
		)
		(zone
			(layer "B.Cu")
			(hatch none 0.5)
			(connect_pads
				(clearance 0)
			)
			(min_thickness 0.25)
			(keepout
				(tracks not_allowed)
				(vias allowed)
				(pads allowed)
				(copperpour not_allowed)
				(footprints allowed)
			)
			(placement
				(enabled no)
				(sheetname "")
			)
			(fill
				(thermal_gap 0.5)
				(thermal_bridge_width 0.5)
				(island_removal_mode 0)
			)
			(polygon
				(pts
					(xy 458.2414 -144.399) (xy 458.2414 -143.891) (xy 457.8604 -143.891) (xy 457.8604 -144.399)
				)
			)
		)
	)
	(footprint ""
		(layer "B.Cu")
		(at 101.244654 -79.60614 180)
		(property "Reference" "C8P11"
			(at 0 0 0)
			(layer "B.SilkS")
			(hide yes)
			(effects
				(font
					(size 1.27 1.27)
				)
				(justify mirror)
			)
		)
		(property "Value" ""
			(at 0 0 0)
			(layer "B.Fab")
			(effects
				(font
					(size 1.27 1.27)
				)
				(justify mirror)
			)
		)
		(duplicate_pad_numbers_are_jumpers no)
		(fp_poly
			(pts
				(xy 0.7239 -0.2159) (xy -0.7239 -0.2159) (xy -0.7239 1.9939) (xy 0.7239 1.9939)
			)
			(stroke
				(width 0)
				(type default)
			)
			(fill no)
			(layer "B.CrtYd")
		)
		(fp_line
			(start 0.7239 1.9939)
			(end -0.7239 1.9939)
			(stroke
				(width 0.1)
				(type default)
			)
			(layer "B.Fab")
		)
		(fp_line
			(start 0.7239 -0.2159)
			(end 0.7239 1.9939)
			(stroke
				(width 0.1)
				(type default)
			)
			(layer "B.Fab")
		)
		(fp_line
			(start -0.7239 1.9939)
			(end -0.7239 -0.2159)
			(stroke
				(width 0.1)
				(type default)
			)
			(layer "B.Fab")
		)
		(fp_line
			(start -0.7239 -0.2159)
			(end 0.7239 -0.2159)
			(stroke
				(width 0.1)
				(type default)
			)
			(layer "B.Fab")
		)
		(pad "1" smd rect
			(at 0 0)
			(size 1.27 1.016)
			(layers "B.Cu" "B.Mask" "B.Paste")
			(net "PVCCIN_CPU1")
		)
		(pad "2" smd rect
			(at 0 1.778)
			(size 1.27 1.016)
			(layers "B.Cu" "B.Mask" "B.Paste")
			(net "GND")
		)
		(zone
			(layer "B.Cu")
			(hatch none 0.5)
			(connect_pads
				(clearance 0)
			)
			(min_thickness 0.25)
			(keepout
				(tracks not_allowed)
				(vias allowed)
				(pads allowed)
				(copperpour not_allowed)
				(footprints allowed)
			)
			(placement
				(enabled no)
				(sheetname "")
			)
			(fill
				(thermal_gap 0.5)
				(thermal_bridge_width 0.5)
				(island_removal_mode 0)
			)
			(polygon
				(pts
					(xy 100.609654 -80.11414) (xy 101.879654 -80.11414) (xy 101.879654 -80.87614) (xy 100.609654 -80.87614)
				)
			)
		)
	)
	(footprint ""
		(layer "B.Cu")
		(at 197.239128 -54.531006 90)
		(property "Reference" "R6R2"
			(at 0 0 90)
			(layer "B.SilkS")
			(hide yes)
			(effects
				(font
					(size 1.27 1.27)
				)
				(justify mirror)
			)
		)
		(property "Value" ""
			(at 0 0 90)
			(layer "B.Fab")
			(effects
				(font
					(size 1.27 1.27)
				)
				(justify mirror)
			)
		)
		(duplicate_pad_numbers_are_jumpers no)
		(fp_rect
			(start 0.2794 -0.1016)
			(end -0.2794 0.9906)
			(stroke
				(width 0)
				(type default)
			)
			(fill no)
			(layer "B.CrtYd")
		)
		(fp_line
			(start 0.2794 -0.1016)
			(end 0.2794 0.9906)
			(stroke
				(width 0.1)
				(type default)
			)
			(layer "B.Fab")
		)
		(fp_line
			(start -0.2794 -0.1016)
			(end 0.2794 -0.1016)
			(stroke
				(width 0.1)
				(type default)
			)
			(layer "B.Fab")
		)
		(fp_line
			(start 0.2794 0.9906)
			(end -0.2794 0.9906)
			(stroke
				(width 0.1)
				(type default)
			)
			(layer "B.Fab")
		)
		(fp_line
			(start -0.2794 0.9906)
			(end -0.2794 -0.1016)
			(stroke
				(width 0.1)
				(type default)
			)
			(layer "B.Fab")
		)
		(pad "1" smd rect
			(at 0 0 270)
			(size 0.508 0.508)
			(layers "B.Cu" "B.Mask" "B.Paste")
			(net "VR_PVCCIN_CPU0_PH1_VCIN")
		)
		(pad "2" smd rect
			(at 0 0.889 270)
			(size 0.508 0.508)
			(layers "B.Cu" "B.Mask" "B.Paste")
			(net "P5V_STBY")
		)
		(zone
			(layer "B.Cu")
			(hatch none 0.5)
			(connect_pads
				(clearance 0)
			)
			(min_thickness 0.25)
			(keepout
				(tracks allowed)
				(vias not_allowed)
				(pads allowed)
				(copperpour not_allowed)
				(footprints allowed)
			)
			(placement
				(enabled no)
				(sheetname "")
			)
			(fill
				(thermal_gap 0.5)
				(thermal_bridge_width 0.5)
				(island_removal_mode 0)
			)
			(polygon
				(pts
					(xy 197.493128 -54.785006) (xy 197.493128 -54.277006) (xy 197.874128 -54.277006) (xy 197.874128 -54.785006)
				)
			)
		)
		(zone
			(layer "B.Cu")
			(hatch none 0.5)
			(connect_pads
				(clearance 0)
			)
			(min_thickness 0.25)
			(keepout
				(tracks not_allowed)
				(vias allowed)
				(pads allowed)
				(copperpour not_allowed)
				(footprints allowed)
			)
			(placement
				(enabled no)
				(sheetname "")
			)
			(fill
				(thermal_gap 0.5)
				(thermal_bridge_width 0.5)
				(island_removal_mode 0)
			)
			(polygon
				(pts
					(xy 197.493128 -54.785006) (xy 197.493128 -54.277006) (xy 197.874128 -54.277006) (xy 197.874128 -54.785006)
				)
			)
		)
	)
)
